# SCM (Grand Teton) — schematic netlist excerpt (pin names and nets, part order shuffled) for the footprints in the layout excerpt that follows; sources: Cadence DE-HDL packaged netlist, KiCad conversion of 12092022_DA0F0TMDCD0_F0T_Management_Board_D_brd_V3_OCP.brd

R104  Q_RES  33.2 1% CHIP  pkg 0402LF  page 30 : A = UART_BMC_5_RXD_BUF_R ; B = UART_BMC_5_RXD_BUF1
R135  Q_RES  0 5% CHIP  pkg 0402LF  page 28 : A = SMB_BMC_MM15_SCL ; B = SMB_BMC_MM15_R1_SCL

(kicad_pcb
	(version 20260206)
	(generator "pcbnew")
	(generator_version "10.0")
	(general
		(thickness 1.6)
		(legacy_teardrops no)
	)
	(paper "A4")
	(title_block
		(title "12092022_DA0F0TMDCD0_F0T_Management_Board_D_brd_V3_OCP.brd")
		(comment 1 "Grand Teton / footprints 1149-1150 of 1440")
	)
	(layers
		(0 "F.Cu" signal "TOP")
		(4 "In1.Cu" signal "GND")
		(6 "In2.Cu" signal "IN1")
		(8 "In3.Cu" signal "GND1")
		(10 "In4.Cu" signal "IN2")
		(12 "In5.Cu" signal "VCC")
		(14 "In6.Cu" signal "VCC1")
		(16 "In7.Cu" signal "IN3")
		(18 "In8.Cu" signal "GND2")
		(20 "In9.Cu" signal "IN4")
		(22 "In10.Cu" signal "GND3")
		(2 "B.Cu" signal "BOTTOM")
		(9 "F.Adhes" user "F.Adhesive")
		(11 "B.Adhes" user "B.Adhesive")
		(13 "F.Paste" user "Package Geometry/Pastemask Top")
		(15 "B.Paste" user "Package Geometry/Pastemask Bottom")
		(5 "F.SilkS" user "Ref Des/Silkscreen Top")
		(7 "B.SilkS" user "Ref Des/Silkscreen Bottom")
		(1 "F.Mask" user "Board Geometry/Soldermask Top")
		(3 "B.Mask" user "Board Geometry/Soldermask Bottom")
		(17 "Dwgs.User" user "User.Drawings")
		(19 "Cmts.User" user "User.Comments")
		(21 "Eco1.User" user "User.Eco1")
		(23 "Eco2.User" user "User.Eco2")
		(25 "Edge.Cuts" user "Board Geometry/Outline")
		(27 "Margin" user)
		(31 "F.CrtYd" user "Package Geometry/Place Bound Top")
		(29 "B.CrtYd" user "Package Geometry/Place Bound Bottom")
		(35 "F.Fab" user "Ref Des/Assembly Top")
		(33 "B.Fab" user "Ref Des/Assembly Bottom")
	)
	(footprint ""
		(layer "B.Cu")
		(at 16.564864 -58.7502 -90)
		(property "Reference" "R135"
			(at 0 0 90)
			(layer "B.SilkS")
			(hide yes)
			(effects
				(font
					(size 1.27 1.27)
				)
				(justify mirror)
			)
		)
		(property "Value" ""
			(at 0 0 90)
			(layer "B.Fab")
			(effects
				(font
					(size 1.27 1.27)
				)
				(justify mirror)
			)
		)
		(duplicate_pad_numbers_are_jumpers no)
		(fp_line
			(start -0.7874 0.4064)
			(end 0.7874 0.4064)
			(stroke
				(width 0.1524)
				(type default)
			)
			(layer "B.SilkS")
		)
		(fp_line
			(start 0.7874 0.4064)
			(end 0.7874 -0.4064)
			(stroke
				(width 0.1524)
				(type default)
			)
			(layer "B.SilkS")
		)
		(fp_line
			(start -0.7874 -0.4064)
			(end -0.7874 0.4064)
			(stroke
				(width 0.1524)
				(type default)
			)
			(layer "B.SilkS")
		)
		(fp_line
			(start 0.7874 -0.4064)
			(end -0.7874 -0.4064)
			(stroke
				(width 0.1524)
				(type default)
			)
			(layer "B.SilkS")
		)
		(fp_line
			(start -0.67945 0.3048)
			(end -0.120396 0.3048)
			(stroke
				(width 0.1)
				(type default)
			)
			(layer "B.Fab")
		)
		(fp_line
			(start -0.120396 0.3048)
			(end -0.120396 0.2794)
			(stroke
				(width 0.1)
				(type default)
			)
			(layer "B.Fab")
		)
		(fp_line
			(start 0.12065 0.3048)
			(end 0.67945 0.3048)
			(stroke
				(width 0.1)
				(type default)
			)
			(layer "B.Fab")
		)
		(fp_line
			(start 0.67945 0.3048)
			(end 0.67945 -0.305054)
			(stroke
				(width 0.1)
				(type default)
			)
			(layer "B.Fab")
		)
		(fp_line
			(start -0.120396 0.2794)
			(end 0.12065 0.2794)
			(stroke
				(width 0.1)
				(type default)
			)
			(layer "B.Fab")
		)
		(fp_line
			(start 0.12065 0.2794)
			(end 0.12065 0.3048)
			(stroke
				(width 0.1)
				(type default)
			)
			(layer "B.Fab")
		)
		(fp_line
			(start -0.12065 -0.2794)
			(end -0.12065 -0.3048)
			(stroke
				(width 0.1)
				(type default)
			)
			(layer "B.Fab")
		)
		(fp_line
			(start 0.12065 -0.2794)
			(end -0.12065 -0.2794)
			(stroke
				(width 0.1)
				(type default)
			)
			(layer "B.Fab")
		)
		(fp_line
			(start -0.67945 -0.3048)
			(end -0.67945 0.3048)
			(stroke
				(width 0.1)
				(type default)
			)
			(layer "B.Fab")
		)
		(fp_line
			(start -0.12065 -0.3048)
			(end -0.67945 -0.3048)
			(stroke
				(width 0.1)
				(type default)
			)
			(layer "B.Fab")
		)
		(fp_line
			(start 0.12065 -0.305054)
			(end 0.12065 -0.2794)
			(stroke
				(width 0.1)
				(type default)
			)
			(layer "B.Fab")
		)
		(fp_line
			(start 0.67945 -0.305054)
			(end 0.12065 -0.305054)
			(stroke
				(width 0.1)
				(type default)
			)
			(layer "B.Fab")
		)
		(pad "1" smd circle
			(at 0.40005 0 90)
			(size 0 0)
			(layers "B.Cu" "B.Mask" "B.Paste")
			(net "SMB_BMC_MM15_SCL")
		)
		(pad "2" smd circle
			(at -0.40005 0 90)
			(size 0 0)
			(layers "B.Cu" "B.Mask" "B.Paste")
			(net "SMB_BMC_MM15_R1_SCL")
		)
	)
	(footprint ""
		(layer "B.Cu")
		(at 11.9126 -25.9842 180)
		(property "Reference" "R104"
			(at 0 0 0)
			(layer "B.SilkS")
			(hide yes)
			(effects
				(font
					(size 1.27 1.27)
				)
				(justify mirror)
			)
		)
		(property "Value" ""
			(at 0 0 0)
			(layer "B.Fab")
			(effects
				(font
					(size 1.27 1.27)
				)
				(justify mirror)
			)
		)
		(duplicate_pad_numbers_are_jumpers no)
		(fp_line
			(start 0.7874 0.4064)
			(end 0.7874 -0.4064)
			(stroke
				(width 0.1524)
				(type default)
			)
			(layer "B.SilkS")
		)
		(fp_line
			(start 0.7874 -0.4064)
			(end -0.7874 -0.4064)
			(stroke
				(width 0.1524)
				(type default)
			)
			(layer "B.SilkS")
		)
		(fp_line
			(start -0.7874 0.4064)
			(end 0.7874 0.4064)
			(stroke
				(width 0.1524)
				(type default)
			)
			(layer "B.SilkS")
		)
		(fp_line
			(start -0.7874 -0.4064)
			(end -0.7874 0.4064)
			(stroke
				(width 0.1524)
				(type default)
			)
			(layer "B.SilkS")
		)
		(fp_line
			(start 0.67945 0.3048)
			(end 0.67945 -0.305054)
			(stroke
				(width 0.1)
				(type default)
			)
			(layer "B.Fab")
		)
		(fp_line
			(start 0.67945 -0.305054)
			(end 0.12065 -0.305054)
			(stroke
				(width 0.1)
				(type default)
			)
			(layer "B.Fab")
		)
		(fp_line
			(start 0.12065 0.3048)
			(end 0.67945 0.3048)
			(stroke
				(width 0.1)
				(type default)
			)
			(layer "B.Fab")
		)
		(fp_line
			(start 0.12065 0.2794)
			(end 0.12065 0.3048)
			(stroke
				(width 0.1)
				(type default)
			)
			(layer "B.Fab")
		)
		(fp_line
			(start 0.12065 -0.2794)
			(end -0.12065 -0.2794)
			(stroke
				(width 0.1)
				(type default)
			)
			(layer "B.Fab")
		)
		(fp_line
			(start 0.12065 -0.305054)
			(end 0.12065 -0.2794)
			(stroke
				(width 0.1)
				(type default)
			)
			(layer "B.Fab")
		)
		(fp_line
			(start -0.120396 0.3048)
			(end -0.120396 0.2794)
			(stroke
				(width 0.1)
				(type default)
			)
			(layer "B.Fab")
		)
		(fp_line
			(start -0.120396 0.2794)
			(end 0.12065 0.2794)
			(stroke
				(width 0.1)
				(type default)
			)
			(layer "B.Fab")
		)
		(fp_line
			(start -0.12065 -0.2794)
			(end -0.12065 -0.3048)
			(stroke
				(width 0.1)
				(type default)
			)
			(layer "B.Fab")
		)
		(fp_line
			(start -0.12065 -0.3048)
			(end -0.67945 -0.3048)
			(stroke
				(width 0.1)
				(type default)
			)
			(layer "B.Fab")
		)
		(fp_line
			(start -0.67945 0.3048)
			(end -0.120396 0.3048)
			(stroke
				(width 0.1)
				(type default)
			)
			(layer "B.Fab")
		)
		(fp_line
			(start -0.67945 -0.3048)
			(end -0.67945 0.3048)
			(stroke
				(width 0.1)
				(type default)
			)
			(layer "B.Fab")
		)
		(pad "1" smd circle
			(at 0.40005 0)
			(size 0 0)
			(layers "B.Cu" "B.Mask" "B.Paste")
			(net "UART_BMC_5_RXD_BUF_R")
		)
		(pad "2" smd circle
			(at -0.40005 0)
			(size 0 0)
			(layers "B.Cu" "B.Mask" "B.Paste")
			(net "UART_BMC_5_RXD_BUF1")
		)
	)
)
